(kicad_pcb
	(version 20260206)
	(generator "pcbnew")
	(generator_version "10.0")
	(general
		(thickness 1.6)
		(legacy_teardrops no)
	)
	(paper "A4")
	(title_block
		(title "01162023_DA0F0TEBIF0_F0T_Expander_BD_F_brd_V02_OCP.brd")
		(comment 1 "Grand Teton / footprints 8781-8788 of 9728")
	)
	(layers
		(0 "F.Cu" signal "TOP")
		(4 "In1.Cu" signal "GND")
		(6 "In2.Cu" signal "VCC")
		(8 "In3.Cu" signal "VCC1")
		(10 "In4.Cu" signal "GND1")
		(12 "In5.Cu" signal "IN1")
		(14 "In6.Cu" signal "GND2")
		(16 "In7.Cu" signal "IN2")
		(18 "In8.Cu" signal "GND3")
		(20 "In9.Cu" signal "IN3")
		(22 "In10.Cu" signal "GND4")
		(24 "In11.Cu" signal "IN4")
		(26 "In12.Cu" signal "GND5")
		(28 "In13.Cu" signal "IN5")
		(30 "In14.Cu" signal "GND6")
		(32 "In15.Cu" signal "IN6")
		(34 "In16.Cu" signal "GND7")
		(2 "B.Cu" signal "BOTTOM")
		(9 "F.Adhes" user "F.Adhesive")
		(11 "B.Adhes" user "B.Adhesive")
		(13 "F.Paste" user "Package Geometry/Pastemask Top")
		(15 "B.Paste" user "Package Geometry/Pastemask Bottom")
		(5 "F.SilkS" user "Ref Des/Silkscreen Top")
		(7 "B.SilkS" user "Ref Des/Silkscreen Bottom")
		(1 "F.Mask" user "Board Geometry/Soldermask Top")
		(3 "B.Mask" user "Board Geometry/Soldermask Bottom")
		(17 "Dwgs.User" user "User.Drawings")
		(19 "Cmts.User" user "User.Comments")
		(21 "Eco1.User" user "User.Eco1")
		(23 "Eco2.User" user "User.Eco2")
		(25 "Edge.Cuts" user "Board Geometry/Outline")
		(27 "Margin" user)
		(31 "F.CrtYd" user "Package Geometry/Place Bound Top")
		(29 "B.CrtYd" user "Package Geometry/Place Bound Bottom")
		(35 "F.Fab" user "Ref Des/Assembly Top")
		(33 "B.Fab" user "Ref Des/Assembly Bottom")
	)
	(footprint ""
		(layer "B.Cu")
		(at 217.235786 -215.254586 180)
		(property "Reference" "R5716"
			(at 0 0 0)
			(layer "B.SilkS")
			(hide yes)
			(effects
				(font
					(size 1.27 1.27)
				)
				(justify mirror)
			)
		)
		(property "Value" ""
			(at 0 0 0)
			(layer "B.Fab")
			(effects
				(font
					(size 1.27 1.27)
				)
				(justify mirror)
			)
		)
		(duplicate_pad_numbers_are_jumpers no)
		(fp_line
			(start 0.7874 0.4064)
			(end 0.7874 -0.4064)
			(stroke
				(width 0.1524)
				(type default)
			)
			(layer "B.SilkS")
		)
		(fp_line
			(start 0.7874 -0.4064)
			(end -0.7874 -0.4064)
			(stroke
				(width 0.1524)
				(type default)
			)
			(layer "B.SilkS")
		)
		(fp_line
			(start -0.7874 0.4064)
			(end 0.7874 0.4064)
			(stroke
				(width 0.1524)
				(type default)
			)
			(layer "B.SilkS")
		)
		(fp_line
			(start -0.7874 -0.4064)
			(end -0.7874 0.4064)
			(stroke
				(width 0.1524)
				(type default)
			)
			(layer "B.SilkS")
		)
		(fp_line
			(start 0.67945 0.3048)
			(end 0.67945 -0.305054)
			(stroke
				(width 0.1)
				(type default)
			)
			(layer "B.Fab")
		)
		(fp_line
			(start 0.67945 -0.305054)
			(end 0.12065 -0.305054)
			(stroke
				(width 0.1)
				(type default)
			)
			(layer "B.Fab")
		)
		(fp_line
			(start 0.12065 0.3048)
			(end 0.67945 0.3048)
			(stroke
				(width 0.1)
				(type default)
			)
			(layer "B.Fab")
		)
		(fp_line
			(start 0.12065 0.2794)
			(end 0.12065 0.3048)
			(stroke
				(width 0.1)
				(type default)
			)
			(layer "B.Fab")
		)
		(fp_line
			(start 0.12065 -0.2794)
			(end -0.12065 -0.2794)
			(stroke
				(width 0.1)
				(type default)
			)
			(layer "B.Fab")
		)
		(fp_line
			(start 0.12065 -0.305054)
			(end 0.12065 -0.2794)
			(stroke
				(width 0.1)
				(type default)
			)
			(layer "B.Fab")
		)
		(fp_line
			(start -0.120396 0.3048)
			(end -0.120396 0.2794)
			(stroke
				(width 0.1)
				(type default)
			)
			(layer "B.Fab")
		)
		(fp_line
			(start -0.120396 0.2794)
			(end 0.12065 0.2794)
			(stroke
				(width 0.1)
				(type default)
			)
			(layer "B.Fab")
		)
		(fp_line
			(start -0.12065 -0.2794)
			(end -0.12065 -0.3048)
			(stroke
				(width 0.1)
				(type default)
			)
			(layer "B.Fab")
		)
		(fp_line
			(start -0.12065 -0.3048)
			(end -0.67945 -0.3048)
			(stroke
				(width 0.1)
				(type default)
			)
			(layer "B.Fab")
		)
		(fp_line
			(start -0.67945 0.3048)
			(end -0.120396 0.3048)
			(stroke
				(width 0.1)
				(type default)
			)
			(layer "B.Fab")
		)
		(fp_line
			(start -0.67945 -0.3048)
			(end -0.67945 0.3048)
			(stroke
				(width 0.1)
				(type default)
			)
			(layer "B.Fab")
		)
		(pad "1" smd circle
			(at 0.40005 0)
			(size 0 0)
			(layers "B.Cu" "B.Mask" "B.Paste")
			(net "BIC_UART_BIC_SEL_R")
		)
		(pad "2" smd circle
			(at -0.40005 0)
			(size 0 0)
			(layers "B.Cu" "B.Mask" "B.Paste")
			(net "BIC_UART_BIC_SEL")
		)
	)
	(footprint ""
		(layer "B.Cu")
		(at 136.403842 -182.052468 -90)
		(property "Reference" "R1121"
			(at 0 0 90)
			(layer "B.SilkS")
			(hide yes)
			(effects
				(font
					(size 1.27 1.27)
				)
				(justify mirror)
			)
		)
		(property "Value" ""
			(at 0 0 90)
			(layer "B.Fab")
			(effects
				(font
					(size 1.27 1.27)
				)
				(justify mirror)
			)
		)
		(duplicate_pad_numbers_are_jumpers no)
		(fp_line
			(start -0.7874 0.4064)
			(end 0.7874 0.4064)
			(stroke
				(width 0.1524)
				(type default)
			)
			(layer "B.SilkS")
		)
		(fp_line
			(start 0.7874 0.4064)
			(end 0.7874 -0.4064)
			(stroke
				(width 0.1524)
				(type default)
			)
			(layer "B.SilkS")
		)
		(fp_line
			(start -0.7874 -0.4064)
			(end -0.7874 0.4064)
			(stroke
				(width 0.1524)
				(type default)
			)
			(layer "B.SilkS")
		)
		(fp_line
			(start 0.7874 -0.4064)
			(end -0.7874 -0.4064)
			(stroke
				(width 0.1524)
				(type default)
			)
			(layer "B.SilkS")
		)
		(fp_line
			(start -0.67945 0.3048)
			(end -0.120396 0.3048)
			(stroke
				(width 0.1)
				(type default)
			)
			(layer "B.Fab")
		)
		(fp_line
			(start -0.120396 0.3048)
			(end -0.120396 0.2794)
			(stroke
				(width 0.1)
				(type default)
			)
			(layer "B.Fab")
		)
		(fp_line
			(start 0.12065 0.3048)
			(end 0.67945 0.3048)
			(stroke
				(width 0.1)
				(type default)
			)
			(layer "B.Fab")
		)
		(fp_line
			(start 0.67945 0.3048)
			(end 0.67945 -0.305054)
			(stroke
				(width 0.1)
				(type default)
			)
			(layer "B.Fab")
		)
		(fp_line
			(start -0.120396 0.2794)
			(end 0.12065 0.2794)
			(stroke
				(width 0.1)
				(type default)
			)
			(layer "B.Fab")
		)
		(fp_line
			(start 0.12065 0.2794)
			(end 0.12065 0.3048)
			(stroke
				(width 0.1)
				(type default)
			)
			(layer "B.Fab")
		)
		(fp_line
			(start -0.12065 -0.2794)
			(end -0.12065 -0.3048)
			(stroke
				(width 0.1)
				(type default)
			)
			(layer "B.Fab")
		)
		(fp_line
			(start 0.12065 -0.2794)
			(end -0.12065 -0.2794)
			(stroke
				(width 0.1)
				(type default)
			)
			(layer "B.Fab")
		)
		(fp_line
			(start -0.67945 -0.3048)
			(end -0.67945 0.3048)
			(stroke
				(width 0.1)
				(type default)
			)
			(layer "B.Fab")
		)
		(fp_line
			(start -0.12065 -0.3048)
			(end -0.67945 -0.3048)
			(stroke
				(width 0.1)
				(type default)
			)
			(layer "B.Fab")
		)
		(fp_line
			(start 0.12065 -0.305054)
			(end 0.12065 -0.2794)
			(stroke
				(width 0.1)
				(type default)
			)
			(layer "B.Fab")
		)
		(fp_line
			(start 0.67945 -0.305054)
			(end 0.12065 -0.305054)
			(stroke
				(width 0.1)
				(type default)
			)
			(layer "B.Fab")
		)
		(pad "1" smd circle
			(at 0.40005 0 90)
			(size 0 0)
			(layers "B.Cu" "B.Mask" "B.Paste")
			(net "FM_DB2000QL_SMB_SA1")
		)
		(pad "2" smd circle
			(at -0.40005 0 90)
			(size 0 0)
			(layers "B.Cu" "B.Mask" "B.Paste")
			(net "P3V3")
		)
	)
	(footprint ""
		(layer "B.Cu")
		(at 278.554942 -293.52494)
		(property "Reference" "C3405"
			(at 0 0 0)
			(layer "B.SilkS")
			(hide yes)
			(effects
				(font
					(size 1.27 1.27)
				)
				(justify mirror)
			)
		)
		(property "Value" ""
			(at 0 0 0)
			(layer "B.Fab")
			(effects
				(font
					(size 1.27 1.27)
				)
				(justify mirror)
			)
		)
		(duplicate_pad_numbers_are_jumpers no)
		(fp_line
			(start -0.299974 -0.150114)
			(end -0.299974 0.150114)
			(stroke
				(width 0.1)
				(type default)
			)
			(layer "B.Fab")
		)
		(fp_line
			(start -0.299974 0.150114)
			(end 0.299974 0.150114)
			(stroke
				(width 0.1)
				(type default)
			)
			(layer "B.Fab")
		)
		(fp_line
			(start 0.299974 -0.150114)
			(end -0.299974 -0.150114)
			(stroke
				(width 0.1)
				(type default)
			)
			(layer "B.Fab")
		)
		(fp_line
			(start 0.299974 0.150114)
			(end 0.299974 -0.150114)
			(stroke
				(width 0.1)
				(type default)
			)
			(layer "B.Fab")
		)
		(pad "1" smd rect
			(at 0.2667 0 180)
			(size 0.3048 0.381)
			(layers "B.Cu" "B.Mask" "B.Paste")
			(net "PCEPLL6_VDDA18_PEX2")
		)
		(pad "2" smd rect
			(at -0.2667 0 180)
			(size 0.3048 0.381)
			(layers "B.Cu" "B.Mask" "B.Paste")
			(net "GND")
		)
	)
	(footprint ""
		(layer "B.Cu")
		(at 283.299916 -290.199826 90)
		(property "Reference" "C1686"
			(at 0 0 90)
			(layer "B.SilkS")
			(hide yes)
			(effects
				(font
					(size 1.27 1.27)
				)
				(justify mirror)
			)
		)
		(property "Value" ""
			(at 0 0 90)
			(layer "B.Fab")
			(effects
				(font
					(size 1.27 1.27)
				)
				(justify mirror)
			)
		)
		(duplicate_pad_numbers_are_jumpers no)
		(fp_line
			(start 0.299974 -0.150114)
			(end -0.299974 -0.150114)
			(stroke
				(width 0.1)
				(type default)
			)
			(layer "B.Fab")
		)
		(fp_line
			(start -0.299974 -0.150114)
			(end -0.299974 0.150114)
			(stroke
				(width 0.1)
				(type default)
			)
			(layer "B.Fab")
		)
		(fp_line
			(start 0.299974 0.150114)
			(end 0.299974 -0.150114)
			(stroke
				(width 0.1)
				(type default)
			)
			(layer "B.Fab")
		)
		(fp_line
			(start -0.299974 0.150114)
			(end 0.299974 0.150114)
			(stroke
				(width 0.1)
				(type default)
			)
			(layer "B.Fab")
		)
		(pad "1" smd rect
			(at 0.2667 0 270)
			(size 0.3048 0.381)
			(layers "B.Cu" "B.Mask" "B.Paste")
			(net "P0V8_SERDES_VDDA_PEX2")
		)
		(pad "2" smd rect
			(at -0.2667 0 270)
			(size 0.3048 0.381)
			(layers "B.Cu" "B.Mask" "B.Paste")
			(net "GND")
		)
	)
	(footprint ""
		(layer "B.Cu")
		(at 335.153 -207.772 90)
		(property "Reference" "R4124"
			(at 0 0 90)
			(layer "B.SilkS")
			(hide yes)
			(effects
				(font
					(size 1.27 1.27)
				)
				(justify mirror)
			)
		)
		(property "Value" ""
			(at 0 0 90)
			(layer "B.Fab")
			(effects
				(font
					(size 1.27 1.27)
				)
				(justify mirror)
			)
		)
		(duplicate_pad_numbers_are_jumpers no)
		(fp_line
			(start 0.7874 -0.4064)
			(end -0.7874 -0.4064)
			(stroke
				(width 0.1524)
				(type default)
			)
			(layer "B.SilkS")
		)
		(fp_line
			(start -0.7874 -0.4064)
			(end -0.7874 0.4064)
			(stroke
				(width 0.1524)
				(type default)
			)
			(layer "B.SilkS")
		)
		(fp_line
			(start 0.7874 0.4064)
			(end 0.7874 -0.4064)
			(stroke
				(width 0.1524)
				(type default)
			)
			(layer "B.SilkS")
		)
		(fp_line
			(start -0.7874 0.4064)
			(end 0.7874 0.4064)
			(stroke
				(width 0.1524)
				(type default)
			)
			(layer "B.SilkS")
		)
		(fp_line
			(start 0.67945 -0.305054)
			(end 0.12065 -0.305054)
			(stroke
				(width 0.1)
				(type default)
			)
			(layer "B.Fab")
		)
		(fp_line
			(start 0.12065 -0.305054)
			(end 0.12065 -0.2794)
			(stroke
				(width 0.1)
				(type default)
			)
			(layer "B.Fab")
		)
		(fp_line
			(start -0.12065 -0.3048)
			(end -0.67945 -0.3048)
			(stroke
				(width 0.1)
				(type default)
			)
			(layer "B.Fab")
		)
		(fp_line
			(start -0.67945 -0.3048)
			(end -0.67945 0.3048)
			(stroke
				(width 0.1)
				(type default)
			)
			(layer "B.Fab")
		)
		(fp_line
			(start 0.12065 -0.2794)
			(end -0.12065 -0.2794)
			(stroke
				(width 0.1)
				(type default)
			)
			(layer "B.Fab")
		)
		(fp_line
			(start -0.12065 -0.2794)
			(end -0.12065 -0.3048)
			(stroke
				(width 0.1)
				(type default)
			)
			(layer "B.Fab")
		)
		(fp_line
			(start 0.12065 0.2794)
			(end 0.12065 0.3048)
			(stroke
				(width 0.1)
				(type default)
			)
			(layer "B.Fab")
		)
		(fp_line
			(start -0.120396 0.2794)
			(end 0.12065 0.2794)
			(stroke
				(width 0.1)
				(type default)
			)
			(layer "B.Fab")
		)
		(fp_line
			(start 0.67945 0.3048)
			(end 0.67945 -0.305054)
			(stroke
				(width 0.1)
				(type default)
			)
			(layer "B.Fab")
		)
		(fp_line
			(start 0.12065 0.3048)
			(end 0.67945 0.3048)
			(stroke
				(width 0.1)
				(type default)
			)
			(layer "B.Fab")
		)
		(fp_line
			(start -0.120396 0.3048)
			(end -0.120396 0.2794)
			(stroke
				(width 0.1)
				(type default)
			)
			(layer "B.Fab")
		)
		(fp_line
			(start -0.67945 0.3048)
			(end -0.120396 0.3048)
			(stroke
				(width 0.1)
				(type default)
			)
			(layer "B.Fab")
		)
		(pad "1" smd circle
			(at 0.40005 0 270)
			(size 0 0)
			(layers "B.Cu" "B.Mask" "B.Paste")
			(net "SSD10_PWRDIS")
		)
		(pad "2" smd circle
			(at -0.40005 0 270)
			(size 0 0)
			(layers "B.Cu" "B.Mask" "B.Paste")
			(net "SSD10_PWRDIS_R")
		)
	)
	(footprint ""
		(layer "B.Cu")
		(at 272.257012 -291.72662 180)
		(property "Reference" "R3471"
			(at 0 0 0)
			(layer "B.SilkS")
			(hide yes)
			(effects
				(font
					(size 1.27 1.27)
				)
				(justify mirror)
			)
		)
		(property "Value" ""
			(at 0 0 0)
			(layer "B.Fab")
			(effects
				(font
					(size 1.27 1.27)
				)
				(justify mirror)
			)
		)
		(duplicate_pad_numbers_are_jumpers no)
		(fp_line
			(start 0.7874 0.4064)
			(end 0.7874 -0.4064)
			(stroke
				(width 0.1524)
				(type default)
			)
			(layer "B.SilkS")
		)
		(fp_line
			(start 0.7874 -0.4064)
			(end -0.7874 -0.4064)
			(stroke
				(width 0.1524)
				(type default)
			)
			(layer "B.SilkS")
		)
		(fp_line
			(start -0.7874 0.4064)
			(end 0.7874 0.4064)
			(stroke
				(width 0.1524)
				(type default)
			)
			(layer "B.SilkS")
		)
		(fp_line
			(start -0.7874 -0.4064)
			(end -0.7874 0.4064)
			(stroke
				(width 0.1524)
				(type default)
			)
			(layer "B.SilkS")
		)
		(fp_line
			(start 0.67945 0.3048)
			(end 0.67945 -0.305054)
			(stroke
				(width 0.1)
				(type default)
			)
			(layer "B.Fab")
		)
		(fp_line
			(start 0.67945 -0.305054)
			(end 0.12065 -0.305054)
			(stroke
				(width 0.1)
				(type default)
			)
			(layer "B.Fab")
		)
		(fp_line
			(start 0.12065 0.3048)
			(end 0.67945 0.3048)
			(stroke
				(width 0.1)
				(type default)
			)
			(layer "B.Fab")
		)
		(fp_line
			(start 0.12065 0.2794)
			(end 0.12065 0.3048)
			(stroke
				(width 0.1)
				(type default)
			)
			(layer "B.Fab")
		)
		(fp_line
			(start 0.12065 -0.2794)
			(end -0.12065 -0.2794)
			(stroke
				(width 0.1)
				(type default)
			)
			(layer "B.Fab")
		)
		(fp_line
			(start 0.12065 -0.305054)
			(end 0.12065 -0.2794)
			(stroke
				(width 0.1)
				(type default)
			)
			(layer "B.Fab")
		)
		(fp_line
			(start -0.120396 0.3048)
			(end -0.120396 0.2794)
			(stroke
				(width 0.1)
				(type default)
			)
			(layer "B.Fab")
		)
		(fp_line
			(start -0.120396 0.2794)
			(end 0.12065 0.2794)
			(stroke
				(width 0.1)
				(type default)
			)
			(layer "B.Fab")
		)
		(fp_line
			(start -0.12065 -0.2794)
			(end -0.12065 -0.3048)
			(stroke
				(width 0.1)
				(type default)
			)
			(layer "B.Fab")
		)
		(fp_line
			(start -0.12065 -0.3048)
			(end -0.67945 -0.3048)
			(stroke
				(width 0.1)
				(type default)
			)
			(layer "B.Fab")
		)
		(fp_line
			(start -0.67945 0.3048)
			(end -0.120396 0.3048)
			(stroke
				(width 0.1)
				(type default)
			)
			(layer "B.Fab")
		)
		(fp_line
			(start -0.67945 -0.3048)
			(end -0.67945 0.3048)
			(stroke
				(width 0.1)
				(type default)
			)
			(layer "B.Fab")
		)
		(pad "1" smd circle
			(at 0.40005 0)
			(size 0 0)
			(layers "B.Cu" "B.Mask" "B.Paste")
			(net "SPI_PEX2_CLK_R")
		)
		(pad "2" smd circle
			(at -0.40005 0)
			(size 0 0)
			(layers "B.Cu" "B.Mask" "B.Paste")
			(net "SPI_PEX2_CLK")
		)
	)
	(footprint ""
		(layer "B.Cu")
		(at 232.482644 -231.225598 -90)
		(property "Reference" "R4518"
			(at 0 0 90)
			(layer "B.SilkS")
			(hide yes)
			(effects
				(font
					(size 1.27 1.27)
				)
				(justify mirror)
			)
		)
		(property "Value" ""
			(at 0 0 90)
			(layer "B.Fab")
			(effects
				(font
					(size 1.27 1.27)
				)
				(justify mirror)
			)
		)
		(duplicate_pad_numbers_are_jumpers no)
		(fp_line
			(start -0.7874 0.4064)
			(end 0.7874 0.4064)
			(stroke
				(width 0.1524)
				(type default)
			)
			(layer "B.SilkS")
		)
		(fp_line
			(start 0.7874 0.4064)
			(end 0.7874 -0.4064)
			(stroke
				(width 0.1524)
				(type default)
			)
			(layer "B.SilkS")
		)
		(fp_line
			(start -0.7874 -0.4064)
			(end -0.7874 0.4064)
			(stroke
				(width 0.1524)
				(type default)
			)
			(layer "B.SilkS")
		)
		(fp_line
			(start 0.7874 -0.4064)
			(end -0.7874 -0.4064)
			(stroke
				(width 0.1524)
				(type default)
			)
			(layer "B.SilkS")
		)
		(fp_line
			(start -0.67945 0.3048)
			(end -0.120396 0.3048)
			(stroke
				(width 0.1)
				(type default)
			)
			(layer "B.Fab")
		)
		(fp_line
			(start -0.120396 0.3048)
			(end -0.120396 0.2794)
			(stroke
				(width 0.1)
				(type default)
			)
			(layer "B.Fab")
		)
		(fp_line
			(start 0.12065 0.3048)
			(end 0.67945 0.3048)
			(stroke
				(width 0.1)
				(type default)
			)
			(layer "B.Fab")
		)
		(fp_line
			(start 0.67945 0.3048)
			(end 0.67945 -0.305054)
			(stroke
				(width 0.1)
				(type default)
			)
			(layer "B.Fab")
		)
		(fp_line
			(start -0.120396 0.2794)
			(end 0.12065 0.2794)
			(stroke
				(width 0.1)
				(type default)
			)
			(layer "B.Fab")
		)
		(fp_line
			(start 0.12065 0.2794)
			(end 0.12065 0.3048)
			(stroke
				(width 0.1)
				(type default)
			)
			(layer "B.Fab")
		)
		(fp_line
			(start -0.12065 -0.2794)
			(end -0.12065 -0.3048)
			(stroke
				(width 0.1)
				(type default)
			)
			(layer "B.Fab")
		)
		(fp_line
			(start 0.12065 -0.2794)
			(end -0.12065 -0.2794)
			(stroke
				(width 0.1)
				(type default)
			)
			(layer "B.Fab")
		)
		(fp_line
			(start -0.67945 -0.3048)
			(end -0.67945 0.3048)
			(stroke
				(width 0.1)
				(type default)
			)
			(layer "B.Fab")
		)
		(fp_line
			(start -0.12065 -0.3048)
			(end -0.67945 -0.3048)
			(stroke
				(width 0.1)
				(type default)
			)
			(layer "B.Fab")
		)
		(fp_line
			(start 0.12065 -0.305054)
			(end 0.12065 -0.2794)
			(stroke
				(width 0.1)
				(type default)
			)
			(layer "B.Fab")
		)
		(fp_line
			(start 0.67945 -0.305054)
			(end 0.12065 -0.305054)
			(stroke
				(width 0.1)
				(type default)
			)
			(layer "B.Fab")
		)
		(pad "1" smd circle
			(at 0.40005 0 90)
			(size 0 0)
			(layers "B.Cu" "B.Mask" "B.Paste")
			(net "SSD4_PWRDIS_BIC")
		)
		(pad "2" smd circle
			(at -0.40005 0 90)
			(size 0 0)
			(layers "B.Cu" "B.Mask" "B.Paste")
			(net "SSD4_PWRDIS_BIC_R")
		)
	)
	(footprint ""
		(layer "B.Cu")
		(at 185.725054 -305.608228 -90)
		(property "Reference" "C3172"
			(at 0 0 90)
			(layer "B.SilkS")
			(hide yes)
			(effects
				(font
					(size 1.27 1.27)
				)
				(justify mirror)
			)
		)
		(property "Value" ""
			(at 0 0 90)
			(layer "B.Fab")
			(effects
				(font
					(size 1.27 1.27)
				)
				(justify mirror)
			)
		)
		(duplicate_pad_numbers_are_jumpers no)
		(fp_line
			(start -0.299974 0.150114)
			(end 0.299974 0.150114)
			(stroke
				(width 0.1)
				(type default)
			)
			(layer "B.Fab")
		)
		(fp_line
			(start 0.299974 0.150114)
			(end 0.299974 -0.150114)
			(stroke
				(width 0.1)
				(type default)
			)
			(layer "B.Fab")
		)
		(fp_line
			(start -0.299974 -0.150114)
			(end -0.299974 0.150114)
			(stroke
				(width 0.1)
				(type default)
			)
			(layer "B.Fab")
		)
		(fp_line
			(start 0.299974 -0.150114)
			(end -0.299974 -0.150114)
			(stroke
				(width 0.1)
				(type default)
			)
			(layer "B.Fab")
		)
		(pad "1" smd rect
			(at 0.2667 0 90)
			(size 0.3048 0.381)
			(layers "B.Cu" "B.Mask" "B.Paste")
			(net "P1V8_VDDA_PEX1")
		)
		(pad "2" smd rect
			(at -0.2667 0 90)
			(size 0.3048 0.381)
			(layers "B.Cu" "B.Mask" "B.Paste")
			(net "GND")
		)
	)
)
